(kicad_pcb
	(version 20260206)
	(generator "pcbnew")
	(generator_version "10.0")
	(general
		(thickness 1.6)
		(legacy_teardrops no)
	)
	(paper "A4")
	(title_block
		(title "01162023_DA0F0TEBIF0_F0T_Expander_BD_F_brd_V02_OCP.brd")
		(comment 1 "Grand Teton / footprints 353-359 of 9728")
	)
	(layers
		(0 "F.Cu" signal "TOP")
		(4 "In1.Cu" signal "GND")
		(6 "In2.Cu" signal "VCC")
		(8 "In3.Cu" signal "VCC1")
		(10 "In4.Cu" signal "GND1")
		(12 "In5.Cu" signal "IN1")
		(14 "In6.Cu" signal "GND2")
		(16 "In7.Cu" signal "IN2")
		(18 "In8.Cu" signal "GND3")
		(20 "In9.Cu" signal "IN3")
		(22 "In10.Cu" signal "GND4")
		(24 "In11.Cu" signal "IN4")
		(26 "In12.Cu" signal "GND5")
		(28 "In13.Cu" signal "IN5")
		(30 "In14.Cu" signal "GND6")
		(32 "In15.Cu" signal "IN6")
		(34 "In16.Cu" signal "GND7")
		(2 "B.Cu" signal "BOTTOM")
		(9 "F.Adhes" user "F.Adhesive")
		(11 "B.Adhes" user "B.Adhesive")
		(13 "F.Paste" user "Package Geometry/Pastemask Top")
		(15 "B.Paste" user "Package Geometry/Pastemask Bottom")
		(5 "F.SilkS" user "Ref Des/Silkscreen Top")
		(7 "B.SilkS" user "Ref Des/Silkscreen Bottom")
		(1 "F.Mask" user "Board Geometry/Soldermask Top")
		(3 "B.Mask" user "Board Geometry/Soldermask Bottom")
		(17 "Dwgs.User" user "User.Drawings")
		(19 "Cmts.User" user "User.Comments")
		(21 "Eco1.User" user "User.Eco1")
		(23 "Eco2.User" user "User.Eco2")
		(25 "Edge.Cuts" user "Board Geometry/Outline")
		(27 "Margin" user)
		(31 "F.CrtYd" user "Package Geometry/Place Bound Top")
		(29 "B.CrtYd" user "Package Geometry/Place Bound Bottom")
		(35 "F.Fab" user "Ref Des/Assembly Top")
		(33 "B.Fab" user "Ref Des/Assembly Bottom")
	)
	(footprint ""
		(layer "F.Cu")
		(at 347.92031 -260.290564)
		(property "Reference" "PR129"
			(at 0 0 0)
			(layer "F.SilkS")
			(hide yes)
			(effects
				(font
					(size 1.27 1.27)
				)
			)
		)
		(property "Value" ""
			(at 0 0 0)
			(layer "F.Fab")
			(effects
				(font
					(size 1.27 1.27)
				)
			)
		)
		(duplicate_pad_numbers_are_jumpers no)
		(fp_line
			(start -0.7874 -0.4064)
			(end 0.7874 -0.4064)
			(stroke
				(width 0.1524)
				(type default)
			)
			(layer "F.SilkS")
		)
		(fp_line
			(start -0.7874 0.4064)
			(end -0.7874 -0.4064)
			(stroke
				(width 0.1524)
				(type default)
			)
			(layer "F.SilkS")
		)
		(fp_line
			(start 0.7874 -0.4064)
			(end 0.7874 0.4064)
			(stroke
				(width 0.1524)
				(type default)
			)
			(layer "F.SilkS")
		)
		(fp_line
			(start 0.7874 0.4064)
			(end -0.7874 0.4064)
			(stroke
				(width 0.1524)
				(type default)
			)
			(layer "F.SilkS")
		)
		(fp_line
			(start -0.67945 -0.305054)
			(end -0.12065 -0.305054)
			(stroke
				(width 0.1)
				(type default)
			)
			(layer "F.Fab")
		)
		(fp_line
			(start -0.67945 0.3048)
			(end -0.67945 -0.305054)
			(stroke
				(width 0.1)
				(type default)
			)
			(layer "F.Fab")
		)
		(fp_line
			(start -0.12065 -0.305054)
			(end -0.12065 -0.2794)
			(stroke
				(width 0.1)
				(type default)
			)
			(layer "F.Fab")
		)
		(fp_line
			(start -0.12065 -0.2794)
			(end 0.12065 -0.2794)
			(stroke
				(width 0.1)
				(type default)
			)
			(layer "F.Fab")
		)
		(fp_line
			(start -0.12065 0.2794)
			(end -0.12065 0.3048)
			(stroke
				(width 0.1)
				(type default)
			)
			(layer "F.Fab")
		)
		(fp_line
			(start -0.12065 0.3048)
			(end -0.67945 0.3048)
			(stroke
				(width 0.1)
				(type default)
			)
			(layer "F.Fab")
		)
		(fp_line
			(start 0.120396 0.2794)
			(end -0.12065 0.2794)
			(stroke
				(width 0.1)
				(type default)
			)
			(layer "F.Fab")
		)
		(fp_line
			(start 0.120396 0.3048)
			(end 0.120396 0.2794)
			(stroke
				(width 0.1)
				(type default)
			)
			(layer "F.Fab")
		)
		(fp_line
			(start 0.12065 -0.3048)
			(end 0.67945 -0.3048)
			(stroke
				(width 0.1)
				(type default)
			)
			(layer "F.Fab")
		)
		(fp_line
			(start 0.12065 -0.2794)
			(end 0.12065 -0.3048)
			(stroke
				(width 0.1)
				(type default)
			)
			(layer "F.Fab")
		)
		(fp_line
			(start 0.67945 -0.3048)
			(end 0.67945 0.3048)
			(stroke
				(width 0.1)
				(type default)
			)
			(layer "F.Fab")
		)
		(fp_line
			(start 0.67945 0.3048)
			(end 0.120396 0.3048)
			(stroke
				(width 0.1)
				(type default)
			)
			(layer "F.Fab")
		)
		(pad "1" smd circle
			(at -0.40005 0)
			(size 0 0)
			(layers "F.Cu" "F.Mask" "F.Paste")
			(net "SH_P0V8_PEX3_VSEN3_R")
		)
		(pad "2" smd circle
			(at 0.40005 0)
			(size 0 0)
			(layers "F.Cu" "F.Mask" "F.Paste")
			(net "P0V8_PEX3_VSEN3")
		)
	)
	(footprint ""
		(layer "F.Cu")
		(at 99.8855 -27.092148 -90)
		(property "Reference" "R5737"
			(at 0 0 270)
			(layer "F.SilkS")
			(hide yes)
			(effects
				(font
					(size 1.27 1.27)
				)
			)
		)
		(property "Value" ""
			(at 0 0 270)
			(layer "F.Fab")
			(effects
				(font
					(size 1.27 1.27)
				)
			)
		)
		(duplicate_pad_numbers_are_jumpers no)
		(fp_line
			(start -0.7874 0.4064)
			(end -0.7874 -0.4064)
			(stroke
				(width 0.1524)
				(type default)
			)
			(layer "F.SilkS")
		)
		(fp_line
			(start 0.7874 0.4064)
			(end -0.7874 0.4064)
			(stroke
				(width 0.1524)
				(type default)
			)
			(layer "F.SilkS")
		)
		(fp_line
			(start -0.7874 -0.4064)
			(end 0.7874 -0.4064)
			(stroke
				(width 0.1524)
				(type default)
			)
			(layer "F.SilkS")
		)
		(fp_line
			(start 0.7874 -0.4064)
			(end 0.7874 0.4064)
			(stroke
				(width 0.1524)
				(type default)
			)
			(layer "F.SilkS")
		)
		(fp_line
			(start -0.67945 0.3048)
			(end -0.67945 -0.305054)
			(stroke
				(width 0.1)
				(type default)
			)
			(layer "F.Fab")
		)
		(fp_line
			(start -0.12065 0.3048)
			(end -0.67945 0.3048)
			(stroke
				(width 0.1)
				(type default)
			)
			(layer "F.Fab")
		)
		(fp_line
			(start 0.120396 0.3048)
			(end 0.120396 0.2794)
			(stroke
				(width 0.1)
				(type default)
			)
			(layer "F.Fab")
		)
		(fp_line
			(start 0.67945 0.3048)
			(end 0.120396 0.3048)
			(stroke
				(width 0.1)
				(type default)
			)
			(layer "F.Fab")
		)
		(fp_line
			(start -0.12065 0.2794)
			(end -0.12065 0.3048)
			(stroke
				(width 0.1)
				(type default)
			)
			(layer "F.Fab")
		)
		(fp_line
			(start 0.120396 0.2794)
			(end -0.12065 0.2794)
			(stroke
				(width 0.1)
				(type default)
			)
			(layer "F.Fab")
		)
		(fp_line
			(start -0.12065 -0.2794)
			(end 0.12065 -0.2794)
			(stroke
				(width 0.1)
				(type default)
			)
			(layer "F.Fab")
		)
		(fp_line
			(start 0.12065 -0.2794)
			(end 0.12065 -0.3048)
			(stroke
				(width 0.1)
				(type default)
			)
			(layer "F.Fab")
		)
		(fp_line
			(start 0.12065 -0.3048)
			(end 0.67945 -0.3048)
			(stroke
				(width 0.1)
				(type default)
			)
			(layer "F.Fab")
		)
		(fp_line
			(start 0.67945 -0.3048)
			(end 0.67945 0.3048)
			(stroke
				(width 0.1)
				(type default)
			)
			(layer "F.Fab")
		)
		(fp_line
			(start -0.67945 -0.305054)
			(end -0.12065 -0.305054)
			(stroke
				(width 0.1)
				(type default)
			)
			(layer "F.Fab")
		)
		(fp_line
			(start -0.12065 -0.305054)
			(end -0.12065 -0.2794)
			(stroke
				(width 0.1)
				(type default)
			)
			(layer "F.Fab")
		)
		(pad "1" smd circle
			(at -0.40005 0 270)
			(size 0 0)
			(layers "F.Cu" "F.Mask" "F.Paste")
			(net "P3V3_SSD3")
		)
		(pad "2" smd circle
			(at 0.40005 0 270)
			(size 0 0)
			(layers "F.Cu" "F.Mask" "F.Paste")
			(net "SSD3_LED_ISO_N")
		)
	)
	(footprint ""
		(layer "F.Cu")
		(at 50.481992 -37.025072)
		(property "Reference" "R5661"
			(at 0 0 0)
			(layer "F.SilkS")
			(hide yes)
			(effects
				(font
					(size 1.27 1.27)
				)
			)
		)
		(property "Value" ""
			(at 0 0 0)
			(layer "F.Fab")
			(effects
				(font
					(size 1.27 1.27)
				)
			)
		)
		(duplicate_pad_numbers_are_jumpers no)
		(fp_line
			(start -0.7874 -0.4064)
			(end 0.7874 -0.4064)
			(stroke
				(width 0.1524)
				(type default)
			)
			(layer "F.SilkS")
		)
		(fp_line
			(start -0.7874 0.4064)
			(end -0.7874 -0.4064)
			(stroke
				(width 0.1524)
				(type default)
			)
			(layer "F.SilkS")
		)
		(fp_line
			(start 0.7874 -0.4064)
			(end 0.7874 0.4064)
			(stroke
				(width 0.1524)
				(type default)
			)
			(layer "F.SilkS")
		)
		(fp_line
			(start 0.7874 0.4064)
			(end -0.7874 0.4064)
			(stroke
				(width 0.1524)
				(type default)
			)
			(layer "F.SilkS")
		)
		(fp_line
			(start -0.67945 -0.305054)
			(end -0.12065 -0.305054)
			(stroke
				(width 0.1)
				(type default)
			)
			(layer "F.Fab")
		)
		(fp_line
			(start -0.67945 0.3048)
			(end -0.67945 -0.305054)
			(stroke
				(width 0.1)
				(type default)
			)
			(layer "F.Fab")
		)
		(fp_line
			(start -0.12065 -0.305054)
			(end -0.12065 -0.2794)
			(stroke
				(width 0.1)
				(type default)
			)
			(layer "F.Fab")
		)
		(fp_line
			(start -0.12065 -0.2794)
			(end 0.12065 -0.2794)
			(stroke
				(width 0.1)
				(type default)
			)
			(layer "F.Fab")
		)
		(fp_line
			(start -0.12065 0.2794)
			(end -0.12065 0.3048)
			(stroke
				(width 0.1)
				(type default)
			)
			(layer "F.Fab")
		)
		(fp_line
			(start -0.12065 0.3048)
			(end -0.67945 0.3048)
			(stroke
				(width 0.1)
				(type default)
			)
			(layer "F.Fab")
		)
		(fp_line
			(start 0.120396 0.2794)
			(end -0.12065 0.2794)
			(stroke
				(width 0.1)
				(type default)
			)
			(layer "F.Fab")
		)
		(fp_line
			(start 0.120396 0.3048)
			(end 0.120396 0.2794)
			(stroke
				(width 0.1)
				(type default)
			)
			(layer "F.Fab")
		)
		(fp_line
			(start 0.12065 -0.3048)
			(end 0.67945 -0.3048)
			(stroke
				(width 0.1)
				(type default)
			)
			(layer "F.Fab")
		)
		(fp_line
			(start 0.12065 -0.2794)
			(end 0.12065 -0.3048)
			(stroke
				(width 0.1)
				(type default)
			)
			(layer "F.Fab")
		)
		(fp_line
			(start 0.67945 -0.3048)
			(end 0.67945 0.3048)
			(stroke
				(width 0.1)
				(type default)
			)
			(layer "F.Fab")
		)
		(fp_line
			(start 0.67945 0.3048)
			(end 0.120396 0.3048)
			(stroke
				(width 0.1)
				(type default)
			)
			(layer "F.Fab")
		)
		(pad "1" smd circle
			(at -0.40005 0)
			(size 0 0)
			(layers "F.Cu" "F.Mask" "F.Paste")
			(net "RST_SMB_SSD_R_N")
		)
		(pad "2" smd circle
			(at 0.40005 0)
			(size 0 0)
			(layers "F.Cu" "F.Mask" "F.Paste")
			(net "RST_SMB_SSD2_N")
		)
	)
	(footprint ""
		(layer "F.Cu")
		(at 268.402816 -90.462354)
		(property "Reference" "R1053"
			(at 0 0 0)
			(layer "F.SilkS")
			(hide yes)
			(effects
				(font
					(size 1.27 1.27)
				)
			)
		)
		(property "Value" ""
			(at 0 0 0)
			(layer "F.Fab")
			(effects
				(font
					(size 1.27 1.27)
				)
			)
		)
		(duplicate_pad_numbers_are_jumpers no)
		(fp_line
			(start -0.7874 -0.4064)
			(end 0.7874 -0.4064)
			(stroke
				(width 0.1524)
				(type default)
			)
			(layer "F.SilkS")
		)
		(fp_line
			(start -0.7874 0.4064)
			(end -0.7874 -0.4064)
			(stroke
				(width 0.1524)
				(type default)
			)
			(layer "F.SilkS")
		)
		(fp_line
			(start 0.7874 -0.4064)
			(end 0.7874 0.4064)
			(stroke
				(width 0.1524)
				(type default)
			)
			(layer "F.SilkS")
		)
		(fp_line
			(start 0.7874 0.4064)
			(end -0.7874 0.4064)
			(stroke
				(width 0.1524)
				(type default)
			)
			(layer "F.SilkS")
		)
		(fp_line
			(start -0.67945 -0.305054)
			(end -0.12065 -0.305054)
			(stroke
				(width 0.1)
				(type default)
			)
			(layer "F.Fab")
		)
		(fp_line
			(start -0.67945 0.3048)
			(end -0.67945 -0.305054)
			(stroke
				(width 0.1)
				(type default)
			)
			(layer "F.Fab")
		)
		(fp_line
			(start -0.12065 -0.305054)
			(end -0.12065 -0.2794)
			(stroke
				(width 0.1)
				(type default)
			)
			(layer "F.Fab")
		)
		(fp_line
			(start -0.12065 -0.2794)
			(end 0.12065 -0.2794)
			(stroke
				(width 0.1)
				(type default)
			)
			(layer "F.Fab")
		)
		(fp_line
			(start -0.12065 0.2794)
			(end -0.12065 0.3048)
			(stroke
				(width 0.1)
				(type default)
			)
			(layer "F.Fab")
		)
		(fp_line
			(start -0.12065 0.3048)
			(end -0.67945 0.3048)
			(stroke
				(width 0.1)
				(type default)
			)
			(layer "F.Fab")
		)
		(fp_line
			(start 0.120396 0.2794)
			(end -0.12065 0.2794)
			(stroke
				(width 0.1)
				(type default)
			)
			(layer "F.Fab")
		)
		(fp_line
			(start 0.120396 0.3048)
			(end 0.120396 0.2794)
			(stroke
				(width 0.1)
				(type default)
			)
			(layer "F.Fab")
		)
		(fp_line
			(start 0.12065 -0.3048)
			(end 0.67945 -0.3048)
			(stroke
				(width 0.1)
				(type default)
			)
			(layer "F.Fab")
		)
		(fp_line
			(start 0.12065 -0.2794)
			(end 0.12065 -0.3048)
			(stroke
				(width 0.1)
				(type default)
			)
			(layer "F.Fab")
		)
		(fp_line
			(start 0.67945 -0.3048)
			(end 0.67945 0.3048)
			(stroke
				(width 0.1)
				(type default)
			)
			(layer "F.Fab")
		)
		(fp_line
			(start 0.67945 0.3048)
			(end 0.120396 0.3048)
			(stroke
				(width 0.1)
				(type default)
			)
			(layer "F.Fab")
		)
		(pad "1" smd circle
			(at -0.40005 0)
			(size 0 0)
			(layers "F.Cu" "F.Mask" "F.Paste")
			(net "FM_CK440_MXCK_25M_100M")
		)
		(pad "2" smd circle
			(at 0.40005 0)
			(size 0 0)
			(layers "F.Cu" "F.Mask" "F.Paste")
			(net "P3V3")
		)
	)
	(footprint ""
		(layer "F.Cu")
		(at 10.11047 -123.947428 180)
		(property "Reference" "PR241"
			(at 0 0 180)
			(layer "F.SilkS")
			(hide yes)
			(effects
				(font
					(size 1.27 1.27)
				)
			)
		)
		(property "Value" ""
			(at 0 0 180)
			(layer "F.Fab")
			(effects
				(font
					(size 1.27 1.27)
				)
			)
		)
		(duplicate_pad_numbers_are_jumpers no)
		(fp_line
			(start 0.7874 0.4064)
			(end -0.7874 0.4064)
			(stroke
				(width 0.1524)
				(type default)
			)
			(layer "F.SilkS")
		)
		(fp_line
			(start 0.7874 -0.4064)
			(end 0.7874 0.4064)
			(stroke
				(width 0.1524)
				(type default)
			)
			(layer "F.SilkS")
		)
		(fp_line
			(start -0.7874 0.4064)
			(end -0.7874 -0.4064)
			(stroke
				(width 0.1524)
				(type default)
			)
			(layer "F.SilkS")
		)
		(fp_line
			(start -0.7874 -0.4064)
			(end 0.7874 -0.4064)
			(stroke
				(width 0.1524)
				(type default)
			)
			(layer "F.SilkS")
		)
		(fp_line
			(start 0.67945 0.3048)
			(end 0.120396 0.3048)
			(stroke
				(width 0.1)
				(type default)
			)
			(layer "F.Fab")
		)
		(fp_line
			(start 0.67945 -0.3048)
			(end 0.67945 0.3048)
			(stroke
				(width 0.1)
				(type default)
			)
			(layer "F.Fab")
		)
		(fp_line
			(start 0.12065 -0.2794)
			(end 0.12065 -0.3048)
			(stroke
				(width 0.1)
				(type default)
			)
			(layer "F.Fab")
		)
		(fp_line
			(start 0.12065 -0.3048)
			(end 0.67945 -0.3048)
			(stroke
				(width 0.1)
				(type default)
			)
			(layer "F.Fab")
		)
		(fp_line
			(start 0.120396 0.3048)
			(end 0.120396 0.2794)
			(stroke
				(width 0.1)
				(type default)
			)
			(layer "F.Fab")
		)
		(fp_line
			(start 0.120396 0.2794)
			(end -0.12065 0.2794)
			(stroke
				(width 0.1)
				(type default)
			)
			(layer "F.Fab")
		)
		(fp_line
			(start -0.12065 0.3048)
			(end -0.67945 0.3048)
			(stroke
				(width 0.1)
				(type default)
			)
			(layer "F.Fab")
		)
		(fp_line
			(start -0.12065 0.2794)
			(end -0.12065 0.3048)
			(stroke
				(width 0.1)
				(type default)
			)
			(layer "F.Fab")
		)
		(fp_line
			(start -0.12065 -0.2794)
			(end 0.12065 -0.2794)
			(stroke
				(width 0.1)
				(type default)
			)
			(layer "F.Fab")
		)
		(fp_line
			(start -0.12065 -0.305054)
			(end -0.12065 -0.2794)
			(stroke
				(width 0.1)
				(type default)
			)
			(layer "F.Fab")
		)
		(fp_line
			(start -0.67945 0.3048)
			(end -0.67945 -0.305054)
			(stroke
				(width 0.1)
				(type default)
			)
			(layer "F.Fab")
		)
		(fp_line
			(start -0.67945 -0.305054)
			(end -0.12065 -0.305054)
			(stroke
				(width 0.1)
				(type default)
			)
			(layer "F.Fab")
		)
		(pad "1" smd circle
			(at -0.40005 0 180)
			(size 0 0)
			(layers "F.Cu" "F.Mask" "F.Paste")
			(net "P3V3_NIC0_OCP")
		)
		(pad "2" smd circle
			(at 0.40005 0 180)
			(size 0 0)
			(layers "F.Cu" "F.Mask" "F.Paste")
			(net "GND")
		)
	)
	(footprint ""
		(layer "F.Cu")
		(at 310.659272 -22.955504 90)
		(property "Reference" "R1713"
			(at 0 0 90)
			(layer "F.SilkS")
			(hide yes)
			(effects
				(font
					(size 1.27 1.27)
				)
			)
		)
		(property "Value" ""
			(at 0 0 90)
			(layer "F.Fab")
			(effects
				(font
					(size 1.27 1.27)
				)
			)
		)
		(duplicate_pad_numbers_are_jumpers no)
		(fp_line
			(start 0.7874 -0.4064)
			(end 0.7874 0.4064)
			(stroke
				(width 0.1524)
				(type default)
			)
			(layer "F.SilkS")
		)
		(fp_line
			(start -0.7874 -0.4064)
			(end 0.7874 -0.4064)
			(stroke
				(width 0.1524)
				(type default)
			)
			(layer "F.SilkS")
		)
		(fp_line
			(start 0.7874 0.4064)
			(end -0.7874 0.4064)
			(stroke
				(width 0.1524)
				(type default)
			)
			(layer "F.SilkS")
		)
		(fp_line
			(start -0.7874 0.4064)
			(end -0.7874 -0.4064)
			(stroke
				(width 0.1524)
				(type default)
			)
			(layer "F.SilkS")
		)
		(fp_line
			(start -0.12065 -0.305054)
			(end -0.12065 -0.2794)
			(stroke
				(width 0.1)
				(type default)
			)
			(layer "F.Fab")
		)
		(fp_line
			(start -0.67945 -0.305054)
			(end -0.12065 -0.305054)
			(stroke
				(width 0.1)
				(type default)
			)
			(layer "F.Fab")
		)
		(fp_line
			(start 0.67945 -0.3048)
			(end 0.67945 0.3048)
			(stroke
				(width 0.1)
				(type default)
			)
			(layer "F.Fab")
		)
		(fp_line
			(start 0.12065 -0.3048)
			(end 0.67945 -0.3048)
			(stroke
				(width 0.1)
				(type default)
			)
			(layer "F.Fab")
		)
		(fp_line
			(start 0.12065 -0.2794)
			(end 0.12065 -0.3048)
			(stroke
				(width 0.1)
				(type default)
			)
			(layer "F.Fab")
		)
		(fp_line
			(start -0.12065 -0.2794)
			(end 0.12065 -0.2794)
			(stroke
				(width 0.1)
				(type default)
			)
			(layer "F.Fab")
		)
		(fp_line
			(start 0.120396 0.2794)
			(end -0.12065 0.2794)
			(stroke
				(width 0.1)
				(type default)
			)
			(layer "F.Fab")
		)
		(fp_line
			(start -0.12065 0.2794)
			(end -0.12065 0.3048)
			(stroke
				(width 0.1)
				(type default)
			)
			(layer "F.Fab")
		)
		(fp_line
			(start 0.67945 0.3048)
			(end 0.120396 0.3048)
			(stroke
				(width 0.1)
				(type default)
			)
			(layer "F.Fab")
		)
		(fp_line
			(start 0.120396 0.3048)
			(end 0.120396 0.2794)
			(stroke
				(width 0.1)
				(type default)
			)
			(layer "F.Fab")
		)
		(fp_line
			(start -0.12065 0.3048)
			(end -0.67945 0.3048)
			(stroke
				(width 0.1)
				(type default)
			)
			(layer "F.Fab")
		)
		(fp_line
			(start -0.67945 0.3048)
			(end -0.67945 -0.305054)
			(stroke
				(width 0.1)
				(type default)
			)
			(layer "F.Fab")
		)
		(pad "1" smd circle
			(at -0.40005 0 90)
			(size 0 0)
			(layers "F.Cu" "F.Mask" "F.Paste")
			(net "SMB_BIC_I2C9_MUX1_SSD10_R_SCL")
		)
		(pad "2" smd circle
			(at 0.40005 0 90)
			(size 0 0)
			(layers "F.Cu" "F.Mask" "F.Paste")
			(net "SMB_ISO_SSD10_SCL")
		)
	)
	(footprint ""
		(layer "F.Cu")
		(at 50.396648 -350.098614 90)
		(property "Reference" "C161"
			(at 0 0 90)
			(layer "F.SilkS")
			(hide yes)
			(effects
				(font
					(size 1.27 1.27)
				)
			)
		)
		(property "Value" ""
			(at 0 0 90)
			(layer "F.Fab")
			(effects
				(font
					(size 1.27 1.27)
				)
			)
		)
		(duplicate_pad_numbers_are_jumpers no)
		(fp_line
			(start 0.299974 -0.150114)
			(end 0.299974 0.150114)
			(stroke
				(width 0.1)
				(type default)
			)
			(layer "F.Fab")
		)
		(fp_line
			(start -0.299974 -0.150114)
			(end 0.299974 -0.150114)
			(stroke
				(width 0.1)
				(type default)
			)
			(layer "F.Fab")
		)
		(fp_line
			(start 0.299974 0.150114)
			(end -0.299974 0.150114)
			(stroke
				(width 0.1)
				(type default)
			)
			(layer "F.Fab")
		)
		(fp_line
			(start -0.299974 0.150114)
			(end -0.299974 -0.150114)
			(stroke
				(width 0.1)
				(type default)
			)
			(layer "F.Fab")
		)
		(pad "1" smd rect
			(at -0.2667 0 90)
			(size 0.3048 0.381)
			(layers "F.Cu" "F.Mask" "F.Paste")
			(net "P5E_PEX0_STN7_TX_DP<127>")
		)
		(pad "2" smd rect
			(at 0.2667 0 90)
			(size 0.3048 0.381)
			(layers "F.Cu" "F.Mask" "F.Paste")
			(net "P5E_PEX0_STN7_TX_C_DP<127>")
		)
	)
)
